FILE_TYPE = CONNECTIVITY;
{Allegro Design Entry HDL 16.6-p007 (v16-6-112F) 10/10/2012}
"PAGE_NUMBER" = 82;
0"NC";
1"M_J_DQS_DP<17:0>";
2"M_J_DQS_DN<17:0>";
3"M_J_MA<17:0>";
4"M_J_DQ<63:0>";
5"M_J_CLK_DN<3:0>";
6"M_J_CS_N<7:0>";
7"M_J_CKE<3:0>";
8"M_J_ODT<3:0>";
9"M_J_BA<1:0>";
10"M_J_BG<1:0>";
11"M_J_CLK_DP<3:0>";
12"M_J_ECC<7:0>";
13"PVDDQ_GHJ\g";
14"PVTT_GHJ\g";
15"GND\g";
16"GND\g";
17"PVPP_GHJ\g";
18"PVPP_GHJ\g";
19"GND\g";
20"P12V_NVDIMM_GHJ\g";
21"GND\g";
22"FM_DIMM_EVENT_COD_N";
23"M_J_VREF";
24"TP_CH_J_DIMM_J1_RFU_2";
25"TP_CH_J_DIMM_J1_RFU_0";
26"TP_CH_J_DIMM_J1_RFU_1";
27"SMB_DDR_GHJ_VPP_SCL";
28"SMB_DDR_GHJ_VPP_SDA";
29"FM_ADR_COMPLETE_GHJ_N";
30"M_J_PAR";
31"M_GHJ_RST_N";
32"M_J_C<2>";
33"M_J_BA<1>";
34"M_J_CLK_DP<2>";
35"M_J_CS_N<7>";
36"M_J_CS_N<6>";
37"M_J_CS_N<5>";
38"M_J_MA<0>";
39"M_J_MA<1>";
40"M_J_ECC<6>";
41"M_J_ECC<5>";
42"M_J_ECC<4>";
43"M_J_ECC<3>";
44"M_J_ECC<2>";
45"M_J_ECC<1>";
46"M_J_ECC<0>";
47"M_J_CKE<3>";
48"M_J_CLK_DP<3>";
49"M_J_BG<0>";
50"M_J_BG<1>";
51"M_J_BA<0>";
52"M_J_MA<2>";
53"M_J_ECC<7>";
54"M_J_ODT<2>";
55"M_J_ODT<3>";
56"M_J_CKE<2>";
57"M_J_CS_N<4>";
58"M_J_CLK_DN<2>";
59"M_J_CLK_DN<3>";
60"M_J_ACT_N";
61"M_J_ALERT_N";
62"M_J_DQ<1>";
63"M_J_DQ<2>";
64"M_J_DQ<0>";
65"M_J_DQ<7>";
66"M_J_DQ<6>";
67"M_J_DQ<3>";
68"M_J_DQ<4>";
69"M_J_DQ<5>";
70"M_J_DQ<13>";
71"M_J_DQ<12>";
72"M_J_DQ<11>";
73"M_J_DQ<10>";
74"M_J_DQ<9>";
75"M_J_DQ<8>";
76"M_J_DQ<18>";
77"M_J_DQ<14>";
78"M_J_DQ<15>";
79"M_J_DQ<17>";
80"M_J_DQ<16>";
81"M_J_DQ<23>";
82"M_J_DQ<21>";
83"M_J_DQ<20>";
84"M_J_DQ<19>";
85"M_J_DQ<22>";
86"M_J_DQ<28>";
87"M_J_DQ<25>";
88"M_J_DQ<24>";
89"M_J_DQ<27>";
90"M_J_DQ<26>";
91"M_J_DQ<29>";
92"M_J_DQ<33>";
93"M_J_DQ<32>";
94"M_J_DQ<31>";
95"M_J_DQ<30>";
96"M_J_DQ<34>";
97"M_J_DQ<35>";
98"M_J_DQ<38>";
99"M_J_DQ<36>";
100"M_J_DQ<37>";
101"M_J_DQ<43>";
102"M_J_DQ<42>";
103"M_J_DQ<40>";
104"M_J_DQ<39>";
105"M_J_DQ<41>";
106"M_J_DQ<46>";
107"M_J_DQ<45>";
108"M_J_DQ<44>";
109"M_J_DQ<48>";
110"M_J_DQ<47>";
111"M_J_MA<12>";
112"M_J_MA<13>";
113"M_J_MA<17>";
114"M_J_MA<3>";
115"M_J_MA<4>";
116"M_J_MA<5>";
117"M_J_MA<6>";
118"M_J_MA<7>";
119"M_J_MA<8>";
120"M_J_MA<9>";
121"M_J_MA<10>";
122"M_J_MA<11>";
123"M_J_MA<14>";
124"M_J_MA<15>";
125"M_J_MA<16>";
126"M_J_DQ<54>";
127"M_J_DQ<53>";
128"M_J_DQ<52>";
129"M_J_DQ<51>";
130"M_J_DQ<50>";
131"M_J_DQ<49>";
132"M_J_DQ<59>";
133"M_J_DQ<56>";
134"M_J_DQ<55>";
135"M_J_DQ<57>";
136"M_J_DQ<58>";
137"M_J_DQ<63>";
138"M_J_DQ<62>";
139"M_J_DQ<61>";
140"M_J_DQ<60>";
141"M_J_DQS_DN<0>";
142"M_J_DQS_DP<0>";
143"M_J_DQS_DN<1>";
144"M_J_DQS_DP<1>";
145"M_J_DQS_DN<2>";
146"M_J_DQS_DP<2>";
147"M_J_DQS_DN<3>";
148"M_J_DQS_DP<3>";
149"M_J_DQS_DN<4>";
150"M_J_DQS_DP<4>";
151"M_J_DQS_DN<5>";
152"M_J_DQS_DP<5>";
153"M_J_DQS_DN<6>";
154"M_J_DQS_DP<6>";
155"M_J_DQS_DN<10>";
156"M_J_DQS_DP<10>";
157"M_J_DQS_DN<11>";
158"M_J_DQS_DP<11>";
159"M_J_DQS_DN<12>";
160"M_J_DQS_DP<12>";
161"M_J_DQS_DN<13>";
162"M_J_DQS_DP<13>";
163"M_J_DQS_DN<14>";
164"M_J_DQS_DP<14>";
165"M_J_DQS_DN<15>";
166"M_J_DQS_DP<15>";
167"M_J_DQS_DN<16>";
168"M_J_DQS_DP<16>";
169"M_J_DQS_DN<17>";
170"M_J_DQS_DN<7>";
171"M_J_DQS_DP<7>";
172"M_J_DQS_DN<8>";
173"M_J_DQS_DP<8>";
174"M_J_DQS_DN<9>";
175"M_J_DQS_DP<9>";
176"M_J_DQS_DP<17>";
%"TAP"
"6","(650,4950)","2","mstr_standard","I10";
;
HDL_TAP"TRUE"
BODY_TYPE"PLUMBING"
CDS_LIB"mstr_standard";
"B \NAC \NWC"1;
"S \NAC"
BN"15"166;
%"TAP"
"6","(-1750,1900)","2","mstr_standard","I100";
;
HDL_TAP"TRUE"
BODY_TYPE"PLUMBING"
CDS_LIB"mstr_standard";
"B \NAC \NWC"4;
"S \NAC"
BN"5"69;
%"TAP"
"6","(-1750,2000)","2","mstr_standard","I101";
;
HDL_TAP"TRUE"
BODY_TYPE"PLUMBING"
CDS_LIB"mstr_standard";
"B \NAC \NWC"4;
"S \NAC"
BN"7"65;
%"TAP"
"6","(-1750,1950)","2","mstr_standard","I102";
;
HDL_TAP"TRUE"
BODY_TYPE"PLUMBING"
CDS_LIB"mstr_standard";
"B \NAC \NWC"4;
"S \NAC"
BN"6"66;
%"TAP"
"6","(-1750,2050)","2","mstr_standard","I103";
;
HDL_TAP"TRUE"
BODY_TYPE"PLUMBING"
CDS_LIB"mstr_standard";
"B \NAC \NWC"4;
"S \NAC"
BN"8"75;
%"TAP"
"6","(-1750,2100)","2","mstr_standard","I104";
;
HDL_TAP"TRUE"
BODY_TYPE"PLUMBING"
CDS_LIB"mstr_standard";
"B \NAC \NWC"4;
"S \NAC"
BN"9"74;
%"TAP"
"6","(-1750,2150)","2","mstr_standard","I105";
;
HDL_TAP"TRUE"
BODY_TYPE"PLUMBING"
CDS_LIB"mstr_standard";
"B \NAC \NWC"4;
"S \NAC"
BN"10"73;
%"TAP"
"6","(-1750,1800)","2","mstr_standard","I106";
;
HDL_TAP"TRUE"
BODY_TYPE"PLUMBING"
CDS_LIB"mstr_standard";
"B \NAC \NWC"4;
"S \NAC"
BN"3"67;
%"TAP"
"6","(-1750,1850)","2","mstr_standard","I107";
;
HDL_TAP"TRUE"
BODY_TYPE"PLUMBING"
CDS_LIB"mstr_standard";
"B \NAC \NWC"4;
"S \NAC"
BN"4"68;
%"TAP"
"6","(-1750,1700)","2","mstr_standard","I108";
;
HDL_TAP"TRUE"
BODY_TYPE"PLUMBING"
CDS_LIB"mstr_standard";
"B \NAC \NWC"4;
"S \NAC"
BN"1"62;
%"TAP"
"6","(-1750,1650)","2","mstr_standard","I109";
;
HDL_TAP"TRUE"
BODY_TYPE"PLUMBING"
CDS_LIB"mstr_standard";
"B \NAC \NWC"4;
"S \NAC"
BN"0"64;
%"TAP"
"6","(650,4850)","2","mstr_standard","I11";
;
HDL_TAP"TRUE"
BODY_TYPE"PLUMBING"
CDS_LIB"mstr_standard";
"B \NAC \NWC"1;
"S \NAC"
BN"14"164;
%"TAP"
"6","(-1750,1750)","2","mstr_standard","I110";
;
HDL_TAP"TRUE"
BODY_TYPE"PLUMBING"
CDS_LIB"mstr_standard";
"B \NAC \NWC"4;
"S \NAC"
BN"2"63;
%"TAP"
"6","(-3250,4750)","0","mstr_standard","I112";
;
HDL_TAP"TRUE"
BODY_TYPE"PLUMBING"
CDS_LIB"mstr_standard";
"B \NAC \NWC"3;
"S \NAC"
BN"16"125;
%"TAP"
"6","(-3250,4800)","0","mstr_standard","I113";
;
HDL_TAP"TRUE"
BODY_TYPE"PLUMBING"
CDS_LIB"mstr_standard";
"B \NAC \NWC"3;
"S \NAC"
BN"17"113;
%"TAP"
"6","(-3250,4700)","0","mstr_standard","I114";
;
HDL_TAP"TRUE"
BODY_TYPE"PLUMBING"
CDS_LIB"mstr_standard";
"B \NAC \NWC"3;
"S \NAC"
BN"15"124;
%"TAP"
"6","(-3250,4650)","0","mstr_standard","I115";
;
HDL_TAP"TRUE"
BODY_TYPE"PLUMBING"
CDS_LIB"mstr_standard";
"B \NAC \NWC"3;
"S \NAC"
BN"14"123;
%"TAP"
"6","(-3250,4600)","0","mstr_standard","I116";
;
HDL_TAP"TRUE"
BODY_TYPE"PLUMBING"
CDS_LIB"mstr_standard";
"B \NAC \NWC"3;
"S \NAC"
BN"13"112;
%"TAP"
"6","(-3250,4500)","0","mstr_standard","I117";
;
HDL_TAP"TRUE"
BODY_TYPE"PLUMBING"
CDS_LIB"mstr_standard";
"B \NAC \NWC"3;
"S \NAC"
BN"11"122;
%"TAP"
"6","(-3250,4550)","0","mstr_standard","I118";
;
HDL_TAP"TRUE"
BODY_TYPE"PLUMBING"
CDS_LIB"mstr_standard";
"B \NAC \NWC"3;
"S \NAC"
BN"12"111;
%"TAP"
"6","(-3250,4450)","0","mstr_standard","I119";
;
HDL_TAP"TRUE"
BODY_TYPE"PLUMBING"
CDS_LIB"mstr_standard";
"B \NAC \NWC"3;
"S \NAC"
BN"10"121;
%"TAP"
"6","(650,4750)","2","mstr_standard","I12";
;
HDL_TAP"TRUE"
BODY_TYPE"PLUMBING"
CDS_LIB"mstr_standard";
"B \NAC \NWC"1;
"S \NAC"
BN"13"162;
%"TAP"
"6","(-3250,4400)","0","mstr_standard","I120";
;
HDL_TAP"TRUE"
BODY_TYPE"PLUMBING"
CDS_LIB"mstr_standard";
"B \NAC \NWC"3;
"S \NAC"
BN"9"120;
%"TAP"
"6","(-3250,4350)","0","mstr_standard","I121";
;
HDL_TAP"TRUE"
BODY_TYPE"PLUMBING"
CDS_LIB"mstr_standard";
"B \NAC \NWC"3;
"S \NAC"
BN"8"119;
%"TAP"
"6","(-3250,4250)","0","mstr_standard","I122";
;
HDL_TAP"TRUE"
BODY_TYPE"PLUMBING"
CDS_LIB"mstr_standard";
"B \NAC \NWC"3;
"S \NAC"
BN"6"117;
%"TAP"
"6","(-3250,4300)","0","mstr_standard","I123";
;
HDL_TAP"TRUE"
BODY_TYPE"PLUMBING"
CDS_LIB"mstr_standard";
"B \NAC \NWC"3;
"S \NAC"
BN"7"118;
%"TAP"
"6","(-3250,4200)","0","mstr_standard","I124";
;
HDL_TAP"TRUE"
BODY_TYPE"PLUMBING"
CDS_LIB"mstr_standard";
"B \NAC \NWC"3;
"S \NAC"
BN"5"116;
%"TAP"
"6","(-3250,4100)","0","mstr_standard","I125";
;
HDL_TAP"TRUE"
BODY_TYPE"PLUMBING"
CDS_LIB"mstr_standard";
"B \NAC \NWC"3;
"S \NAC"
BN"3"114;
%"TAP"
"6","(-3250,4150)","0","mstr_standard","I126";
;
HDL_TAP"TRUE"
BODY_TYPE"PLUMBING"
CDS_LIB"mstr_standard";
"B \NAC \NWC"3;
"S \NAC"
BN"4"115;
%"TAP"
"6","(-3250,4050)","0","mstr_standard","I127";
;
HDL_TAP"TRUE"
BODY_TYPE"PLUMBING"
CDS_LIB"mstr_standard";
"B \NAC \NWC"3;
"S \NAC"
BN"2"52;
%"TAP"
"6","(-3250,3950)","0","mstr_standard","I128";
;
HDL_TAP"TRUE"
BODY_TYPE"PLUMBING"
CDS_LIB"mstr_standard";
"B \NAC \NWC"3;
"S \NAC"
BN"0"38;
%"TAP"
"6","(-3250,4000)","0","mstr_standard","I129";
;
HDL_TAP"TRUE"
BODY_TYPE"PLUMBING"
CDS_LIB"mstr_standard";
"B \NAC \NWC"3;
"S \NAC"
BN"1"39;
%"TAP"
"6","(650,4650)","2","mstr_standard","I13";
;
HDL_TAP"TRUE"
BODY_TYPE"PLUMBING"
CDS_LIB"mstr_standard";
"B \NAC \NWC"1;
"S \NAC"
BN"12"160;
%"TAP"
"6","(-3250,3850)","0","mstr_standard","I131";
;
HDL_TAP"TRUE"
BODY_TYPE"PLUMBING"
CDS_LIB"mstr_standard";
"B \NAC \NWC"9;
"S \NAC"
BN"1"33;
%"TAP"
"6","(-3250,3800)","0","mstr_standard","I132";
;
HDL_TAP"TRUE"
BODY_TYPE"PLUMBING"
CDS_LIB"mstr_standard";
"B \NAC \NWC"9;
"S \NAC"
BN"0"51;
%"TAP"
"6","(-3250,3700)","0","mstr_standard","I133";
;
HDL_TAP"TRUE"
BODY_TYPE"PLUMBING"
CDS_LIB"mstr_standard";
"B \NAC \NWC"10;
"S \NAC"
BN"0"49;
%"TAP"
"6","(-3250,3750)","0","mstr_standard","I134";
;
HDL_TAP"TRUE"
BODY_TYPE"PLUMBING"
CDS_LIB"mstr_standard";
"B \NAC \NWC"10;
"S \NAC"
BN"1"50;
%"TAP"
"6","(-3300,2700)","0","mstr_standard","I138";
;
HDL_TAP"TRUE"
BODY_TYPE"PLUMBING"
CDS_LIB"mstr_standard";
"B \NAC \NWC"12;
"S \NAC"
BN"6"40;
%"TAP"
"6","(-3300,2750)","0","mstr_standard","I139";
;
HDL_TAP"TRUE"
BODY_TYPE"PLUMBING"
CDS_LIB"mstr_standard";
"B \NAC \NWC"12;
"S \NAC"
BN"7"53;
%"PVDDQ_GHJ"
"1","(-1400,2575)","0","mstr_symbols","I14";
;
HDL_POWER"PVDDQ_GHJ"
ROOM"DDR4_CH_J"
BODY_TYPE"PLUMBING"
CDS_LIB"mstr_symbols"
BOM_COST"MEM"
VOLTAGE"1.2V";
"G\NAC"13;
%"TAP"
"6","(-3300,2650)","0","mstr_standard","I140";
;
HDL_TAP"TRUE"
BODY_TYPE"PLUMBING"
CDS_LIB"mstr_standard";
"B \NAC \NWC"12;
"S \NAC"
BN"5"41;
%"TAP"
"6","(-3300,2600)","0","mstr_standard","I141";
;
HDL_TAP"TRUE"
BODY_TYPE"PLUMBING"
CDS_LIB"mstr_standard";
"B \NAC \NWC"12;
"S \NAC"
BN"4"42;
%"TAP"
"6","(-3300,2550)","0","mstr_standard","I142";
;
HDL_TAP"TRUE"
BODY_TYPE"PLUMBING"
CDS_LIB"mstr_standard";
"B \NAC \NWC"12;
"S \NAC"
BN"3"43;
%"TAP"
"6","(-3300,2450)","0","mstr_standard","I143";
;
HDL_TAP"TRUE"
BODY_TYPE"PLUMBING"
CDS_LIB"mstr_standard";
"B \NAC \NWC"12;
"S \NAC"
BN"1"45;
%"TAP"
"6","(-3300,2500)","0","mstr_standard","I144";
;
HDL_TAP"TRUE"
BODY_TYPE"PLUMBING"
CDS_LIB"mstr_standard";
"B \NAC \NWC"12;
"S \NAC"
BN"2"44;
%"TAP"
"6","(-3300,2400)","0","mstr_standard","I145";
;
HDL_TAP"TRUE"
BODY_TYPE"PLUMBING"
CDS_LIB"mstr_standard";
"B \NAC \NWC"12;
"S \NAC"
BN"0"46;
%"TAP"
"6","(-3250,3600)","0","mstr_standard","I152";
;
HDL_TAP"TRUE"
BODY_TYPE"PLUMBING"
CDS_LIB"mstr_standard";
"B \NAC \NWC"11;
"S \NAC"
BN"3"48;
%"TAP"
"6","(-3250,3500)","0","mstr_standard","I153";
;
HDL_TAP"TRUE"
BODY_TYPE"PLUMBING"
CDS_LIB"mstr_standard";
"B \NAC \NWC"11;
"S \NAC"
BN"2"34;
%"TAP"
"6","(-3450,3550)","0","mstr_standard","I154";
;
HDL_TAP"TRUE"
BODY_TYPE"PLUMBING"
CDS_LIB"mstr_standard";
"B \NAC \NWC"5;
"S \NAC"
BN"3"59;
%"TAP"
"6","(-3450,3450)","0","mstr_standard","I155";
;
HDL_TAP"TRUE"
BODY_TYPE"PLUMBING"
CDS_LIB"mstr_standard";
"B \NAC \NWC"5;
"S \NAC"
BN"2"58;
%"TAP"
"6","(-3300,3300)","0","mstr_standard","I158";
;
HDL_TAP"TRUE"
BODY_TYPE"PLUMBING"
CDS_LIB"mstr_standard";
"B \NAC \NWC"6;
"S \NAC"
BN"7"35;
%"TAP"
"6","(-3300,3250)","0","mstr_standard","I159";
;
HDL_TAP"TRUE"
BODY_TYPE"PLUMBING"
CDS_LIB"mstr_standard";
"B \NAC \NWC"6;
"S \NAC"
BN"6"36;
%"PVTT_GHJ"
"1","(-1200,2750)","0","mstr_symbols","I16";
;
HDL_POWER"PVTT_GHJ"
ROOM"DDR4_CH_J"
BODY_TYPE"PLUMBING"
CDS_LIB"mstr_symbols"
BOM_COST"MEM"
VOLTAGE"0.6V";
"G\NAC"14;
%"TAP"
"6","(-3300,3200)","0","mstr_standard","I160";
;
HDL_TAP"TRUE"
BODY_TYPE"PLUMBING"
CDS_LIB"mstr_standard";
"B \NAC \NWC"6;
"S \NAC"
BN"5"37;
%"TAP"
"6","(-3300,3150)","0","mstr_standard","I161";
;
HDL_TAP"TRUE"
BODY_TYPE"PLUMBING"
CDS_LIB"mstr_standard";
"B \NAC \NWC"6;
"S \NAC"
BN"4"57;
%"TAP"
"6","(-3300,3050)","0","mstr_standard","I162";
;
HDL_TAP"TRUE"
BODY_TYPE"PLUMBING"
CDS_LIB"mstr_standard";
"B \NAC \NWC"7;
"S \NAC"
BN"3"47;
%"TAP"
"6","(-3300,3000)","0","mstr_standard","I165";
;
HDL_TAP"TRUE"
BODY_TYPE"PLUMBING"
CDS_LIB"mstr_standard";
"B \NAC \NWC"7;
"S \NAC"
BN"2"56;
%"TAP"
"6","(-3300,2900)","0","mstr_standard","I166";
;
HDL_TAP"TRUE"
BODY_TYPE"PLUMBING"
CDS_LIB"mstr_standard";
"B \NAC \NWC"8;
"S \NAC"
BN"3"55;
%"TAP"
"6","(-3300,2850)","0","mstr_standard","I168";
;
HDL_TAP"TRUE"
BODY_TYPE"PLUMBING"
CDS_LIB"mstr_standard";
"B \NAC \NWC"8;
"S \NAC"
BN"2"54;
%"TAP"
"6","(850,4600)","2","mstr_standard","I17";
;
HDL_TAP"TRUE"
BODY_TYPE"PLUMBING"
CDS_LIB"mstr_standard";
"B \NAC \NWC"2;
"S \NAC"
BN"12"159;
%"SCONN288_H44441003"
"4","(-350,2050)","0","mstr_sconn","I171";
;
CDS_SEC"4"
ROOM"DDR4_CH_J"
CDS_LOCATION"J9U2"
SEC"4"
SEC_TYPE"PIP"
CDS_LIB"mstr_sconn"
BOM_COST"MEM"
PACK_TYPE"PIP"
MATERIAL"SCONN"
PART_NUMBER"H44441-003"
LOCATION"J9U2";
"VDD<0>"
$PN"236"13;
"VDD<6>"
$PN"220"13;
"VDD<10>"
$PN"209"13;
"VDD<13>"
$PN"92"13;
"VDD<16>"
$PN"85"13;
"VDD<19>"
$PN"76"13;
"VDD<23>"
$PN"64"13;
"VDD<25>"
$PN"59"13;
"VTT<0>"
$PN"221"14;
"12V<1>"
$PN"1"20;
"12V<0>"
$PN"145"20;
"VDD<24>"
$PN"61"13;
"VDD<22>"
$PN"67"13;
"VDD<21>"
$PN"70"13;
"VDD<20>"
$PN"73"13;
"VDD<18>"
$PN"80"13;
"VDD<17>"
$PN"83"13;
"VDD<15>"
$PN"88"13;
"VDD<14>"
$PN"90"13;
"VDD<12>"
$PN"204"13;
"VDD<11>"
$PN"206"13;
"VDD<9>"
$PN"212"13;
"VDD<8>"
$PN"215"13;
"VDD<7>"
$PN"217"13;
"VDD<5>"
$PN"223"13;
"VDD<4>"
$PN"226"13;
"VDD<3>"
$PN"229"13;
"VDD<2>"
$PN"231"13;
"VDD<1>"
$PN"233"13;
"VPP<4>"
$PN"142"17;
"VPP<3>"
$PN"143"17;
"VPP<2>"
$PN"288"17;
"VPP<1>"
$PN"286"17;
"VPP<0>"
$PN"287"17;
"VTT<1>"
$PN"77"14;
%"GND"
"1","(2450,1050)","2","mstr_symbols","I172";
;
HDL_POWER"GND"
ROOM"DDR4_CH_J"
BODY_TYPE"PLUMBING"
BOM_COST"MEM"
CDS_LIB"mstr_symbols"
SIZE"1B"
VOLTAGE"0";
"A\NAC"15;
%"GND"
"1","(-4500,1150)","0","mstr_symbols","I179";
;
HDL_POWER"GND"
ROOM"DDR4_CH_J"
BODY_TYPE"PLUMBING"
BOM_COST"MEM"
SIZE"1B"
CDS_LIB"mstr_symbols"
VOLTAGE"0";
"A\NAC"16;
%"TAP"
"6","(850,4500)","2","mstr_standard","I18";
;
HDL_TAP"TRUE"
BODY_TYPE"PLUMBING"
CDS_LIB"mstr_standard";
"B \NAC \NWC"2;
"S \NAC"
BN"11"157;
%"CAP_A"
"1","(-4500,1450)","2","dev_discrete","I180";
;
ROOM"DDR4_CH_J"
$SEC"1"
CDS_SEC"1"
CDS_LIB"dev_discrete"
BOM_COST"MEM"
CDS_LOCATION"C1G19"
MATERIAL"X7R"
VOLTAGE"25V"
PACK_TYPE"0402V"
TOLERANCE"10%"
VALUE"0.01UF"
PART_NUMBER"A36096-045"
LOCATION"C1G19";
"B"
$PN"2"16;
"A"
$PN"1"23;
%"PVPP_GHJ"
"1","(-1050,3025)","0","mstr_symbols","I181";
;
HDL_POWER"PVPP_GHJ"
ROOM"DDR4_CH_K"
BODY_TYPE"PLUMBING"
CDS_LIB"mstr_symbols"
BOM_COST"MEM"
VOLTAGE"2.5V";
"G\NAC"17;
%"PVPP_GHJ"
"1","(-5200,2150)","0","mstr_symbols","I182";
;
HDL_POWER"PVPP_GHJ"
ROOM"DDR4_CH_J"
BODY_TYPE"PLUMBING"
CDS_LIB"mstr_symbols"
BOM_COST"MEM"
VOLTAGE"2.5V";
"G\NAC"18;
%"SCONN288_H44441003"
"1","(-2500,3150)","0","mstr_sconn","I187";
;
CDS_SEC"1"
ROOM"DDR4_CH_J"
CDS_LOCATION"J9U2"
SEC"1"
SEC_TYPE"PIP"
CDS_LIB"mstr_sconn"
BOM_COST"MEM"
PACK_TYPE"PIP"
MATERIAL"SCONN"
PART_NUMBER"H44441-003"
LOCATION"J9U2";
"DQ<63>"
$PN"280"137;
"BA<1>"
$PN"224"33;
"CK1N"
$PN"219"59;
"CK0P"
$PN"74"34;
"S3_N_C<1>"
$PN"237"35;
"S2_N_C<0>"
$PN"93"36;
"S1_N"
$PN"89"37;
"DQ<29>"
$PN"181"91;
"DQ<28>"
$PN"36"86;
"C<2>"
$PN"235"32;
"A0"
$PN"79"38;
"A1"
$PN"72"39;
"A12"
$PN"65"111;
"A13"
$PN"232"112;
"A17"
$PN"234"113;
"A3"
$PN"71"114;
"A4"
$PN"214"115;
"A5"
$PN"213"116;
"A6"
$PN"69"117;
"A7"
$PN"211"118;
"A8"
$PN"68"119;
"A9"
$PN"66"120;
"CB<6>"
$PN"54"40;
"CB<5>"
$PN"192"41;
"CB<4>"
$PN"47"42;
"CB<3>"
$PN"201"43;
"CB<2>"
$PN"56"44;
"CB<1>"
$PN"194"45;
"CB<0>"
$PN"49"46;
"CK0N"
$PN"75"58;
"CKE<1>"
$PN"203"47;
"DQ<62>"
$PN"135"138;
"DQ<61>"
$PN"273"139;
"DQ<60>"
$PN"128"140;
"DQ<59>"
$PN"282"132;
"DQ<56>"
$PN"130"133;
"DQ<55>"
$PN"269"134;
"DQ<46>"
$PN"113"106;
"DQ<45>"
$PN"251"107;
"DQ<44>"
$PN"106"108;
"DQ<43>"
$PN"260"101;
"DQ<42>"
$PN"115"102;
"DQ<41>"
$PN"253"105;
"DQ<40>"
$PN"108"103;
"DQ<39>"
$PN"247"104;
"DQ<37>"
$PN"240"100;
"DQ<34>"
$PN"104"96;
"DQ<33>"
$PN"242"92;
"DQ<32>"
$PN"97"93;
"DQ<31>"
$PN"188"94;
"DQ<30>"
$PN"43"95;
"DQ<25>"
$PN"183"87;
"DQ<24>"
$PN"38"88;
"DQ<23>"
$PN"177"81;
"DQ<22>"
$PN"32"85;
"DQ<21>"
$PN"170"82;
"DQ<20>"
$PN"25"83;
"DQ<19>"
$PN"179"84;
"DQ<18>"
$PN"34"76;
"DQ<16>"
$PN"27"80;
"DQ<14>"
$PN"21"77;
"DQ<13>"
$PN"159"70;
"DQ<12>"
$PN"14"71;
"DQ<11>"
$PN"168"72;
"DQ<10>"
$PN"23"73;
"DQ<9>"
$PN"161"74;
"DQ<8>"
$PN"16"75;
"DQ<7>"
$PN"155"65;
"DQ<6>"
$PN"10"66;
"EVENT_N"
$PN"78"22;
"PAR"
$PN"222"30;
"RESET_N"
$PN"58"31;
"RFU<2>"
$PN"144"24;
"SCL"
$PN"141"27;
"SDA"
$PN"285"28;
"VREFCA"
$PN"146"23;
"CK1P"
$PN"218"48;
"BG<0>"
$PN"63"49;
"BG<1>"
$PN"207"50;
"BA<0>"
$PN"81"51;
"SA<0>"
$PN"139"18;
"VDDSPD"
$PN"284"18;
"SA<2>"
$PN"238"18;
"SA<1>"
$PN"140"19;
"DQ<1>"
$PN"150"62;
"DQ<0>"
$PN"5"64;
"ACT_N"
$PN"62"60;
"ALERT_N"
$PN"208"61;
"A2"
$PN"216"52;
"DQ<35>"
$PN"249"97;
"DQ<36>"
$PN"95"99;
"DQ<38>"
$PN"102"98;
"A10"
$PN"225"121;
"A11"
$PN"210"122;
"A14_WE_N"
$PN"228"123;
"A15_CAS_N"
$PN"86"124;
"A16_RAS_N"
$PN"82"125;
"CB<7>"
$PN"199"53;
"ODT<0>"
$PN"87"54;
"ODT<1>"
$PN"91"55;
"CKE<0>"
$PN"60"56;
"S0_N"
$PN"84"57;
"DQ<27>"
$PN"190"89;
"DQ<26>"
$PN"45"90;
"DQ<15>"
$PN"166"78;
"DQ<17>"
$PN"172"79;
"RFU<0>"
$PN"205"25;
"RFU<1>"
$PN"227"26;
"SAVE_N_NC"
$PN"230"29;
"DQ<57>"
$PN"275"135;
"DQ<58>"
$PN"137"136;
"DQ<54>"
$PN"124"126;
"DQ<53>"
$PN"262"127;
"DQ<52>"
$PN"117"128;
"DQ<51>"
$PN"271"129;
"DQ<50>"
$PN"126"130;
"DQ<49>"
$PN"264"131;
"DQ<48>"
$PN"119"109;
"DQ<47>"
$PN"258"110;
"DQ<2>"
$PN"12"63;
"DQ<3>"
$PN"157"67;
"DQ<4>"
$PN"3"68;
"DQ<5>"
$PN"148"69;
%"SCONN288_H44441003"
"3","(1750,2350)","0","mstr_sconn","I188";
;
CDS_SEC"3"
ROOM"DDR4_CH_J"
CDS_LOCATION"J9U2"
SEC"3"
SEC_TYPE"PIP"
CDS_LIB"mstr_sconn"
BOM_COST"MEM"
PACK_TYPE"PIP"
MATERIAL"SCONN"
PART_NUMBER"H44441-003"
LOCATION"J9U2";
"VSS<46>"
$PN"147"15;
"VSS<45>"
$PN"149"15;
"VSS<87>"
$PN"15"21;
"VSS<86>"
$PN"17"21;
"VSS<85>"
$PN"20"21;
"VSS<84>"
$PN"22"21;
"VSS<83>"
$PN"24"21;
"VSS<82>"
$PN"26"21;
"VSS<81>"
$PN"28"21;
"VSS<80>"
$PN"31"21;
"VSS<79>"
$PN"33"21;
"VSS<78>"
$PN"35"21;
"VSS<77>"
$PN"37"21;
"VSS<76>"
$PN"39"21;
"VSS<75>"
$PN"42"21;
"VSS<74>"
$PN"44"21;
"VSS<73>"
$PN"46"21;
"VSS<72>"
$PN"48"21;
"VSS<71>"
$PN"50"21;
"VSS<70>"
$PN"53"21;
"VSS<69>"
$PN"55"21;
"VSS<68>"
$PN"57"21;
"VSS<67>"
$PN"94"21;
"VSS<66>"
$PN"96"21;
"VSS<65>"
$PN"98"21;
"VSS<64>"
$PN"101"21;
"VSS<63>"
$PN"103"21;
"VSS<62>"
$PN"105"21;
"VSS<61>"
$PN"107"21;
"VSS<60>"
$PN"109"21;
"VSS<59>"
$PN"112"21;
"VSS<58>"
$PN"114"21;
"VSS<57>"
$PN"116"21;
"VSS<56>"
$PN"118"21;
"VSS<55>"
$PN"120"21;
"VSS<54>"
$PN"123"21;
"VSS<53>"
$PN"125"21;
"VSS<52>"
$PN"127"21;
"VSS<51>"
$PN"129"21;
"VSS<50>"
$PN"131"21;
"VSS<49>"
$PN"134"21;
"VSS<48>"
$PN"136"21;
"VSS<47>"
$PN"138"21;
"VSS<44>"
$PN"151"15;
"VSS<43>"
$PN"154"15;
"VSS<42>"
$PN"156"15;
"VSS<41>"
$PN"158"15;
"VSS<40>"
$PN"160"15;
"VSS<39>"
$PN"162"15;
"VSS<38>"
$PN"165"15;
"VSS<37>"
$PN"167"15;
"VSS<36>"
$PN"169"15;
"VSS<35>"
$PN"171"15;
"VSS<34>"
$PN"173"15;
"VSS<33>"
$PN"176"15;
"VSS<32>"
$PN"178"15;
"VSS<31>"
$PN"180"15;
"VSS<30>"
$PN"182"15;
"VSS<29>"
$PN"184"15;
"VSS<28>"
$PN"187"15;
"VSS<27>"
$PN"189"15;
"VSS<26>"
$PN"191"15;
"VSS<25>"
$PN"193"15;
"VSS<24>"
$PN"195"15;
"VSS<23>"
$PN"198"15;
"VSS<22>"
$PN"200"15;
"VSS<21>"
$PN"202"15;
"VSS<20>"
$PN"239"15;
"VSS<19>"
$PN"241"15;
"VSS<18>"
$PN"243"15;
"VSS<17>"
$PN"246"15;
"VSS<16>"
$PN"248"15;
"VSS<15>"
$PN"250"15;
"VSS<14>"
$PN"252"15;
"VSS<13>"
$PN"254"15;
"VSS<12>"
$PN"257"15;
"VSS<11>"
$PN"259"15;
"VSS<10>"
$PN"261"15;
"VSS<9>"
$PN"263"15;
"VSS<8>"
$PN"265"15;
"VSS<7>"
$PN"268"15;
"VSS<6>"
$PN"270"15;
"VSS<5>"
$PN"272"15;
"VSS<4>"
$PN"274"15;
"VSS<3>"
$PN"276"15;
"VSS<2>"
$PN"279"15;
"VSS<1>"
$PN"281"15;
"VSS<0>"
$PN"283"15;
"VSS<88>"
$PN"13"21;
"VSS<89>"
$PN"11"21;
"VSS<90>"
$PN"9"21;
"VSS<91>"
$PN"6"21;
"VSS<92>"
$PN"4"21;
"VSS<93>"
$PN"2"21;
%"GND"
"1","(-5200,1800)","0","mstr_symbols","I189";
;
HDL_POWER"GND"
ROOM"DDR4_CH_J"
BODY_TYPE"PLUMBING"
CDS_LIB"mstr_symbols"
SIZE"1B"
BOM_COST"MEM"
VOLTAGE"0";
"A\NAC"19;
%"TAP"
"6","(850,4400)","2","mstr_standard","I19";
;
HDL_TAP"TRUE"
BODY_TYPE"PLUMBING"
CDS_LIB"mstr_standard";
"B \NAC \NWC"2;
"S \NAC"
BN"10"155;
%"P12V_NVDIMM_GHJ"
"1","(350,3025)","0","mstr_symbols","I190";
;
HDL_POWER"P12V_NVDIMM_GHJ"
BODY_TYPE"PLUMBING"
CDS_LIB"mstr_symbols"
VOLTAGE"12.0";
"G\NAC"20;
%"TAP"
"6","(850,4200)","2","mstr_standard","I20";
;
HDL_TAP"TRUE"
BODY_TYPE"PLUMBING"
CDS_LIB"mstr_standard";
"B \NAC \NWC"2;
"S \NAC"
BN"8"172;
%"TAP"
"6","(850,4300)","2","mstr_standard","I21";
;
HDL_TAP"TRUE"
BODY_TYPE"PLUMBING"
CDS_LIB"mstr_standard";
"B \NAC \NWC"2;
"S \NAC"
BN"9"174;
%"TAP"
"6","(650,4550)","2","mstr_standard","I22";
;
HDL_TAP"TRUE"
BODY_TYPE"PLUMBING"
CDS_LIB"mstr_standard";
"B \NAC \NWC"1;
"S \NAC"
BN"11"158;
%"TAP"
"6","(650,4450)","2","mstr_standard","I23";
;
HDL_TAP"TRUE"
BODY_TYPE"PLUMBING"
CDS_LIB"mstr_standard";
"B \NAC \NWC"1;
"S \NAC"
BN"10"156;
%"TAP"
"6","(650,4350)","2","mstr_standard","I24";
;
HDL_TAP"TRUE"
BODY_TYPE"PLUMBING"
CDS_LIB"mstr_standard";
"B \NAC \NWC"1;
"S \NAC"
BN"9"175;
%"TAP"
"6","(650,4250)","2","mstr_standard","I25";
;
HDL_TAP"TRUE"
BODY_TYPE"PLUMBING"
CDS_LIB"mstr_standard";
"B \NAC \NWC"1;
"S \NAC"
BN"8"173;
%"TAP"
"6","(650,4150)","2","mstr_standard","I26";
;
HDL_TAP"TRUE"
BODY_TYPE"PLUMBING"
CDS_LIB"mstr_standard";
"B \NAC \NWC"1;
"S \NAC"
BN"7"171;
%"TAP"
"6","(850,4100)","2","mstr_standard","I27";
;
HDL_TAP"TRUE"
BODY_TYPE"PLUMBING"
CDS_LIB"mstr_standard";
"B \NAC \NWC"2;
"S \NAC"
BN"7"170;
%"TAP"
"6","(850,4000)","2","mstr_standard","I28";
;
HDL_TAP"TRUE"
BODY_TYPE"PLUMBING"
CDS_LIB"mstr_standard";
"B \NAC \NWC"2;
"S \NAC"
BN"6"153;
%"TAP"
"6","(850,3900)","2","mstr_standard","I29";
;
HDL_TAP"TRUE"
BODY_TYPE"PLUMBING"
CDS_LIB"mstr_standard";
"B \NAC \NWC"2;
"S \NAC"
BN"5"151;
%"TAP"
"6","(850,5100)","2","mstr_standard","I3";
;
HDL_TAP"TRUE"
BODY_TYPE"PLUMBING"
CDS_LIB"mstr_standard";
"B \NAC \NWC"2;
"S \NAC"
BN"17"169;
%"TAP"
"6","(850,3700)","2","mstr_standard","I30";
;
HDL_TAP"TRUE"
BODY_TYPE"PLUMBING"
CDS_LIB"mstr_standard";
"B \NAC \NWC"2;
"S \NAC"
BN"3"147;
%"TAP"
"6","(850,3800)","2","mstr_standard","I31";
;
HDL_TAP"TRUE"
BODY_TYPE"PLUMBING"
CDS_LIB"mstr_standard";
"B \NAC \NWC"2;
"S \NAC"
BN"4"149;
%"TAP"
"6","(650,4050)","2","mstr_standard","I32";
;
HDL_TAP"TRUE"
BODY_TYPE"PLUMBING"
CDS_LIB"mstr_standard";
"B \NAC \NWC"1;
"S \NAC"
BN"6"154;
%"TAP"
"6","(650,3950)","2","mstr_standard","I33";
;
HDL_TAP"TRUE"
BODY_TYPE"PLUMBING"
CDS_LIB"mstr_standard";
"B \NAC \NWC"1;
"S \NAC"
BN"5"152;
%"TAP"
"6","(650,3850)","2","mstr_standard","I34";
;
HDL_TAP"TRUE"
BODY_TYPE"PLUMBING"
CDS_LIB"mstr_standard";
"B \NAC \NWC"1;
"S \NAC"
BN"4"150;
%"TAP"
"6","(650,3750)","2","mstr_standard","I35";
;
HDL_TAP"TRUE"
BODY_TYPE"PLUMBING"
CDS_LIB"mstr_standard";
"B \NAC \NWC"1;
"S \NAC"
BN"3"148;
%"TAP"
"6","(650,3650)","2","mstr_standard","I36";
;
HDL_TAP"TRUE"
BODY_TYPE"PLUMBING"
CDS_LIB"mstr_standard";
"B \NAC \NWC"1;
"S \NAC"
BN"2"146;
%"TAP"
"6","(850,3500)","2","mstr_standard","I37";
;
HDL_TAP"TRUE"
BODY_TYPE"PLUMBING"
CDS_LIB"mstr_standard";
"B \NAC \NWC"2;
"S \NAC"
BN"1"143;
%"TAP"
"6","(850,3600)","2","mstr_standard","I38";
;
HDL_TAP"TRUE"
BODY_TYPE"PLUMBING"
CDS_LIB"mstr_standard";
"B \NAC \NWC"2;
"S \NAC"
BN"2"145;
%"TAP"
"6","(850,3400)","2","mstr_standard","I39";
;
HDL_TAP"TRUE"
BODY_TYPE"PLUMBING"
CDS_LIB"mstr_standard";
"B \NAC \NWC"2;
"S \NAC"
BN"0"141;
%"TAP"
"6","(850,5000)","2","mstr_standard","I4";
;
HDL_TAP"TRUE"
BODY_TYPE"PLUMBING"
CDS_LIB"mstr_standard";
"B \NAC \NWC"2;
"S \NAC"
BN"16"167;
%"TAP"
"6","(650,3550)","2","mstr_standard","I40";
;
HDL_TAP"TRUE"
BODY_TYPE"PLUMBING"
CDS_LIB"mstr_standard";
"B \NAC \NWC"1;
"S \NAC"
BN"1"144;
%"TAP"
"6","(650,3450)","2","mstr_standard","I41";
;
HDL_TAP"TRUE"
BODY_TYPE"PLUMBING"
CDS_LIB"mstr_standard";
"B \NAC \NWC"1;
"S \NAC"
BN"0"142;
%"GND"
"1","(1050,1050)","2","mstr_symbols","I44";
;
HDL_POWER"GND"
ROOM"DDR4_CH_J"
BODY_TYPE"PLUMBING"
BOM_COST"MEM"
CDS_LIB"mstr_symbols"
SIZE"1B"
VOLTAGE"0";
"A\NAC"21;
%"TAP"
"6","(-1750,4750)","2","mstr_standard","I46";
;
HDL_TAP"TRUE"
BODY_TYPE"PLUMBING"
CDS_LIB"mstr_standard";
"B \NAC \NWC"4;
"S \NAC"
BN"62"138;
%"TAP"
"6","(-1750,4800)","2","mstr_standard","I47";
;
HDL_TAP"TRUE"
BODY_TYPE"PLUMBING"
CDS_LIB"mstr_standard";
"B \NAC \NWC"4;
"S \NAC"
BN"63"137;
%"TAP"
"6","(-1750,4650)","2","mstr_standard","I48";
;
HDL_TAP"TRUE"
BODY_TYPE"PLUMBING"
CDS_LIB"mstr_standard";
"B \NAC \NWC"4;
"S \NAC"
BN"60"140;
%"TAP"
"6","(-1750,4700)","2","mstr_standard","I49";
;
HDL_TAP"TRUE"
BODY_TYPE"PLUMBING"
CDS_LIB"mstr_standard";
"B \NAC \NWC"4;
"S \NAC"
BN"61"139;
%"TAP"
"6","(850,4900)","2","mstr_standard","I5";
;
HDL_TAP"TRUE"
BODY_TYPE"PLUMBING"
CDS_LIB"mstr_standard";
"B \NAC \NWC"2;
"S \NAC"
BN"15"165;
%"TAP"
"6","(-1750,4600)","2","mstr_standard","I50";
;
HDL_TAP"TRUE"
BODY_TYPE"PLUMBING"
CDS_LIB"mstr_standard";
"B \NAC \NWC"4;
"S \NAC"
BN"59"132;
%"TAP"
"6","(-1750,4550)","2","mstr_standard","I51";
;
HDL_TAP"TRUE"
BODY_TYPE"PLUMBING"
CDS_LIB"mstr_standard";
"B \NAC \NWC"4;
"S \NAC"
BN"58"136;
%"TAP"
"6","(-1750,4500)","2","mstr_standard","I52";
;
HDL_TAP"TRUE"
BODY_TYPE"PLUMBING"
CDS_LIB"mstr_standard";
"B \NAC \NWC"4;
"S \NAC"
BN"57"135;
%"TAP"
"6","(-1750,4300)","2","mstr_standard","I53";
;
HDL_TAP"TRUE"
BODY_TYPE"PLUMBING"
CDS_LIB"mstr_standard";
"B \NAC \NWC"4;
"S \NAC"
BN"53"127;
%"TAP"
"6","(-1750,4350)","2","mstr_standard","I54";
;
HDL_TAP"TRUE"
BODY_TYPE"PLUMBING"
CDS_LIB"mstr_standard";
"B \NAC \NWC"4;
"S \NAC"
BN"54"126;
%"TAP"
"6","(-1750,4250)","2","mstr_standard","I55";
;
HDL_TAP"TRUE"
BODY_TYPE"PLUMBING"
CDS_LIB"mstr_standard";
"B \NAC \NWC"4;
"S \NAC"
BN"52"128;
%"TAP"
"6","(-1750,4400)","2","mstr_standard","I56";
;
HDL_TAP"TRUE"
BODY_TYPE"PLUMBING"
CDS_LIB"mstr_standard";
"B \NAC \NWC"4;
"S \NAC"
BN"55"134;
%"TAP"
"6","(-1750,4450)","2","mstr_standard","I57";
;
HDL_TAP"TRUE"
BODY_TYPE"PLUMBING"
CDS_LIB"mstr_standard";
"B \NAC \NWC"4;
"S \NAC"
BN"56"133;
%"TAP"
"6","(-1750,4000)","2","mstr_standard","I58";
;
HDL_TAP"TRUE"
BODY_TYPE"PLUMBING"
CDS_LIB"mstr_standard";
"B \NAC \NWC"4;
"S \NAC"
BN"47"110;
%"TAP"
"6","(-1750,4050)","2","mstr_standard","I59";
;
HDL_TAP"TRUE"
BODY_TYPE"PLUMBING"
CDS_LIB"mstr_standard";
"B \NAC \NWC"4;
"S \NAC"
BN"48"109;
%"TAP"
"6","(850,4800)","2","mstr_standard","I6";
;
HDL_TAP"TRUE"
BODY_TYPE"PLUMBING"
CDS_LIB"mstr_standard";
"B \NAC \NWC"2;
"S \NAC"
BN"14"163;
%"TAP"
"6","(-1750,3950)","2","mstr_standard","I60";
;
HDL_TAP"TRUE"
BODY_TYPE"PLUMBING"
CDS_LIB"mstr_standard";
"B \NAC \NWC"4;
"S \NAC"
BN"46"106;
%"TAP"
"6","(-1750,4100)","2","mstr_standard","I61";
;
HDL_TAP"TRUE"
BODY_TYPE"PLUMBING"
CDS_LIB"mstr_standard";
"B \NAC \NWC"4;
"S \NAC"
BN"49"131;
%"TAP"
"6","(-1750,4150)","2","mstr_standard","I62";
;
HDL_TAP"TRUE"
BODY_TYPE"PLUMBING"
CDS_LIB"mstr_standard";
"B \NAC \NWC"4;
"S \NAC"
BN"50"130;
%"TAP"
"6","(-1750,4200)","2","mstr_standard","I63";
;
HDL_TAP"TRUE"
BODY_TYPE"PLUMBING"
CDS_LIB"mstr_standard";
"B \NAC \NWC"4;
"S \NAC"
BN"51"129;
%"SCONN288_H44441003"
"2","(-50,4300)","0","mstr_sconn","I64";
;
CDS_SEC"2"
ROOM"DDR4_CH_J"
CDS_LOCATION"J9U2"
SEC"2"
SEC_TYPE"PIP"
CDS_LIB"mstr_sconn"
BOM_COST"MEM"
PACK_TYPE"PIP"
MATERIAL"SCONN"
PART_NUMBER"H44441-003"
LOCATION"J9U2";
"DQS0N"
$PN"152"141;
"DQS0P"
$PN"153"142;
"DQS10N"
$PN"19"155;
"DQS10P"
$PN"18"156;
"DQS11N"
$PN"30"157;
"DQS11P"
$PN"29"158;
"DQS12N"
$PN"41"159;
"DQS12P"
$PN"40"160;
"DQS13N"
$PN"100"161;
"DQS13P"
$PN"99"162;
"DQS14N"
$PN"111"163;
"DQS14P"
$PN"110"164;
"DQS15N"
$PN"122"165;
"DQS15P"
$PN"121"166;
"DQS16N"
$PN"133"167;
"DQS16P"
$PN"132"168;
"DQS17N"
$PN"52"169;
"DQS17P"
$PN"51"176;
"DQS1N"
$PN"163"143;
"DQS1P"
$PN"164"144;
"DQS2N"
$PN"174"145;
"DQS2P"
$PN"175"146;
"DQS3N"
$PN"185"147;
"DQS3P"
$PN"186"148;
"DQS4N"
$PN"244"149;
"DQS4P"
$PN"245"150;
"DQS5N"
$PN"255"151;
"DQS5P"
$PN"256"152;
"DQS6N"
$PN"266"153;
"DQS6P"
$PN"267"154;
"DQS7N"
$PN"277"170;
"DQS7P"
$PN"278"171;
"DQS8N"
$PN"196"172;
"DQS8P"
$PN"197"173;
"DQS9N"
$PN"8"174;
"DQS9P"
$PN"7"175;
%"TAP"
"6","(-1750,3800)","2","mstr_standard","I65";
;
HDL_TAP"TRUE"
BODY_TYPE"PLUMBING"
CDS_LIB"mstr_standard";
"B \NAC \NWC"4;
"S \NAC"
BN"43"101;
%"TAP"
"6","(-1750,3750)","2","mstr_standard","I66";
;
HDL_TAP"TRUE"
BODY_TYPE"PLUMBING"
CDS_LIB"mstr_standard";
"B \NAC \NWC"4;
"S \NAC"
BN"42"102;
%"TAP"
"6","(-1750,3700)","2","mstr_standard","I67";
;
HDL_TAP"TRUE"
BODY_TYPE"PLUMBING"
CDS_LIB"mstr_standard";
"B \NAC \NWC"4;
"S \NAC"
BN"41"105;
%"TAP"
"6","(-1750,3850)","2","mstr_standard","I68";
;
HDL_TAP"TRUE"
BODY_TYPE"PLUMBING"
CDS_LIB"mstr_standard";
"B \NAC \NWC"4;
"S \NAC"
BN"44"108;
%"TAP"
"6","(-1750,3900)","2","mstr_standard","I69";
;
HDL_TAP"TRUE"
BODY_TYPE"PLUMBING"
CDS_LIB"mstr_standard";
"B \NAC \NWC"4;
"S \NAC"
BN"45"107;
%"TAP"
"6","(850,4700)","2","mstr_standard","I7";
;
HDL_TAP"TRUE"
BODY_TYPE"PLUMBING"
CDS_LIB"mstr_standard";
"B \NAC \NWC"2;
"S \NAC"
BN"13"161;
%"TAP"
"6","(-1750,3550)","2","mstr_standard","I70";
;
HDL_TAP"TRUE"
BODY_TYPE"PLUMBING"
CDS_LIB"mstr_standard";
"B \NAC \NWC"4;
"S \NAC"
BN"38"98;
%"TAP"
"6","(-1750,3500)","2","mstr_standard","I71";
;
HDL_TAP"TRUE"
BODY_TYPE"PLUMBING"
CDS_LIB"mstr_standard";
"B \NAC \NWC"4;
"S \NAC"
BN"37"100;
%"TAP"
"6","(-1750,3450)","2","mstr_standard","I72";
;
HDL_TAP"TRUE"
BODY_TYPE"PLUMBING"
CDS_LIB"mstr_standard";
"B \NAC \NWC"4;
"S \NAC"
BN"36"99;
%"TAP"
"6","(-1750,3650)","2","mstr_standard","I73";
;
HDL_TAP"TRUE"
BODY_TYPE"PLUMBING"
CDS_LIB"mstr_standard";
"B \NAC \NWC"4;
"S \NAC"
BN"40"103;
%"TAP"
"6","(-1750,3600)","2","mstr_standard","I74";
;
HDL_TAP"TRUE"
BODY_TYPE"PLUMBING"
CDS_LIB"mstr_standard";
"B \NAC \NWC"4;
"S \NAC"
BN"39"104;
%"TAP"
"6","(-1750,3300)","2","mstr_standard","I75";
;
HDL_TAP"TRUE"
BODY_TYPE"PLUMBING"
CDS_LIB"mstr_standard";
"B \NAC \NWC"4;
"S \NAC"
BN"33"92;
%"TAP"
"6","(-1750,3250)","2","mstr_standard","I76";
;
HDL_TAP"TRUE"
BODY_TYPE"PLUMBING"
CDS_LIB"mstr_standard";
"B \NAC \NWC"4;
"S \NAC"
BN"32"93;
%"TAP"
"6","(-1750,3200)","2","mstr_standard","I77";
;
HDL_TAP"TRUE"
BODY_TYPE"PLUMBING"
CDS_LIB"mstr_standard";
"B \NAC \NWC"4;
"S \NAC"
BN"31"94;
%"TAP"
"6","(-1750,3400)","2","mstr_standard","I78";
;
HDL_TAP"TRUE"
BODY_TYPE"PLUMBING"
CDS_LIB"mstr_standard";
"B \NAC \NWC"4;
"S \NAC"
BN"35"97;
%"TAP"
"6","(-1750,3350)","2","mstr_standard","I79";
;
HDL_TAP"TRUE"
BODY_TYPE"PLUMBING"
CDS_LIB"mstr_standard";
"B \NAC \NWC"4;
"S \NAC"
BN"34"96;
%"TAP"
"6","(650,5050)","2","mstr_standard","I8";
;
HDL_TAP"TRUE"
BODY_TYPE"PLUMBING"
CDS_LIB"mstr_standard";
"B \NAC \NWC"1;
"S \NAC"
BN"16"168;
%"TAP"
"6","(-1750,3000)","2","mstr_standard","I80";
;
HDL_TAP"TRUE"
BODY_TYPE"PLUMBING"
CDS_LIB"mstr_standard";
"B \NAC \NWC"4;
"S \NAC"
BN"27"89;
%"TAP"
"6","(-1750,3050)","2","mstr_standard","I81";
;
HDL_TAP"TRUE"
BODY_TYPE"PLUMBING"
CDS_LIB"mstr_standard";
"B \NAC \NWC"4;
"S \NAC"
BN"28"86;
%"TAP"
"6","(-1750,2950)","2","mstr_standard","I82";
;
HDL_TAP"TRUE"
BODY_TYPE"PLUMBING"
CDS_LIB"mstr_standard";
"B \NAC \NWC"4;
"S \NAC"
BN"26"90;
%"TAP"
"6","(-1750,3100)","2","mstr_standard","I83";
;
HDL_TAP"TRUE"
BODY_TYPE"PLUMBING"
CDS_LIB"mstr_standard";
"B \NAC \NWC"4;
"S \NAC"
BN"29"91;
%"TAP"
"6","(-1750,3150)","2","mstr_standard","I84";
;
HDL_TAP"TRUE"
BODY_TYPE"PLUMBING"
CDS_LIB"mstr_standard";
"B \NAC \NWC"4;
"S \NAC"
BN"30"95;
%"TAP"
"6","(-1750,2750)","2","mstr_standard","I85";
;
HDL_TAP"TRUE"
BODY_TYPE"PLUMBING"
CDS_LIB"mstr_standard";
"B \NAC \NWC"4;
"S \NAC"
BN"22"85;
%"TAP"
"6","(-1750,2800)","2","mstr_standard","I86";
;
HDL_TAP"TRUE"
BODY_TYPE"PLUMBING"
CDS_LIB"mstr_standard";
"B \NAC \NWC"4;
"S \NAC"
BN"23"81;
%"TAP"
"6","(-1750,2700)","2","mstr_standard","I87";
;
HDL_TAP"TRUE"
BODY_TYPE"PLUMBING"
CDS_LIB"mstr_standard";
"B \NAC \NWC"4;
"S \NAC"
BN"21"82;
%"TAP"
"6","(-1750,2900)","2","mstr_standard","I88";
;
HDL_TAP"TRUE"
BODY_TYPE"PLUMBING"
CDS_LIB"mstr_standard";
"B \NAC \NWC"4;
"S \NAC"
BN"25"87;
%"TAP"
"6","(-1750,2850)","2","mstr_standard","I89";
;
HDL_TAP"TRUE"
BODY_TYPE"PLUMBING"
CDS_LIB"mstr_standard";
"B \NAC \NWC"4;
"S \NAC"
BN"24"88;
%"TAP"
"6","(650,5150)","2","mstr_standard","I9";
;
HDL_TAP"TRUE"
BODY_TYPE"PLUMBING"
CDS_LIB"mstr_standard";
"B \NAC \NWC"1;
"S \NAC"
BN"17"176;
%"TAP"
"6","(-1750,2450)","2","mstr_standard","I90";
;
HDL_TAP"TRUE"
BODY_TYPE"PLUMBING"
CDS_LIB"mstr_standard";
"B \NAC \NWC"4;
"S \NAC"
BN"16"80;
%"TAP"
"6","(-1750,2500)","2","mstr_standard","I91";
;
HDL_TAP"TRUE"
BODY_TYPE"PLUMBING"
CDS_LIB"mstr_standard";
"B \NAC \NWC"4;
"S \NAC"
BN"17"79;
%"TAP"
"6","(-1750,2550)","2","mstr_standard","I92";
;
HDL_TAP"TRUE"
BODY_TYPE"PLUMBING"
CDS_LIB"mstr_standard";
"B \NAC \NWC"4;
"S \NAC"
BN"18"76;
%"TAP"
"6","(-1750,2600)","2","mstr_standard","I93";
;
HDL_TAP"TRUE"
BODY_TYPE"PLUMBING"
CDS_LIB"mstr_standard";
"B \NAC \NWC"4;
"S \NAC"
BN"19"84;
%"TAP"
"6","(-1750,2650)","2","mstr_standard","I94";
;
HDL_TAP"TRUE"
BODY_TYPE"PLUMBING"
CDS_LIB"mstr_standard";
"B \NAC \NWC"4;
"S \NAC"
BN"20"83;
%"TAP"
"6","(-1750,2200)","2","mstr_standard","I95";
;
HDL_TAP"TRUE"
BODY_TYPE"PLUMBING"
CDS_LIB"mstr_standard";
"B \NAC \NWC"4;
"S \NAC"
BN"11"72;
%"TAP"
"6","(-1750,2300)","2","mstr_standard","I96";
;
HDL_TAP"TRUE"
BODY_TYPE"PLUMBING"
CDS_LIB"mstr_standard";
"B \NAC \NWC"4;
"S \NAC"
BN"13"70;
%"TAP"
"6","(-1750,2250)","2","mstr_standard","I97";
;
HDL_TAP"TRUE"
BODY_TYPE"PLUMBING"
CDS_LIB"mstr_standard";
"B \NAC \NWC"4;
"S \NAC"
BN"12"71;
%"TAP"
"6","(-1750,2350)","2","mstr_standard","I98";
;
HDL_TAP"TRUE"
BODY_TYPE"PLUMBING"
CDS_LIB"mstr_standard";
"B \NAC \NWC"4;
"S \NAC"
BN"14"77;
%"TAP"
"6","(-1750,2400)","2","mstr_standard","I99";
;
HDL_TAP"TRUE"
BODY_TYPE"PLUMBING"
CDS_LIB"mstr_standard";
"B \NAC \NWC"4;
"S \NAC"
BN"15"78;
END.
